# T6G (Grand Teton) — schematic netlist excerpt (pin names and nets, part order shuffled) for the footprints in the layout excerpt that follows; sources: Cadence DE-HDL packaged netlist, KiCad conversion of 04192023_DAF0TMB3IC0_F0TG_MB_C_brd_V02_OCP.brd

PR264  Q_RES  2.2 1% CHIP  pkg 0402LF  page 219 : A = PVDDCR_CPU1_P1_PVCC ; B = PVDDCR_CPU1_P1_VCC4
C1028  Q_CAP  100UF 4V 20% X6S  pkg C0805  page 312 : A = P0V9_CPU0_RT_2D ; B = GND
R1031  Q_RES  4.7K 5% CHIP  pkg 0201LF  page 287 : A = TEST0_RT_CPU0_P1 ; B = GND

(kicad_pcb
	(version 20260206)
	(generator "pcbnew")
	(generator_version "10.0")
	(general
		(thickness 1.6)
		(legacy_teardrops no)
	)
	(paper "A4")
	(title_block
		(title "04192023_DAF0TMB3IC0_F0TG_MB_C_brd_V02_OCP.brd")
		(comment 1 "Grand Teton / footprints 7388-7390 of 8354")
	)
	(layers
		(0 "F.Cu" signal "TOP")
		(4 "In1.Cu" signal "GND")
		(6 "In2.Cu" signal "IN1")
		(8 "In3.Cu" signal "GND1")
		(10 "In4.Cu" signal "IN2")
		(12 "In5.Cu" signal "GND2")
		(14 "In6.Cu" signal "IN3")
		(16 "In7.Cu" signal "GND3")
		(18 "In8.Cu" signal "VCC")
		(20 "In9.Cu" signal "VCC1")
		(22 "In10.Cu" signal "GND4")
		(24 "In11.Cu" signal "IN4")
		(26 "In12.Cu" signal "GND5")
		(28 "In13.Cu" signal "IN5")
		(30 "In14.Cu" signal "GND6")
		(32 "In15.Cu" signal "IN6")
		(34 "In16.Cu" signal "GND7")
		(2 "B.Cu" signal "BOTTOM")
		(9 "F.Adhes" user "F.Adhesive")
		(11 "B.Adhes" user "B.Adhesive")
		(13 "F.Paste" user "Package Geometry/Pastemask Top")
		(15 "B.Paste" user "Package Geometry/Pastemask Bottom")
		(5 "F.SilkS" user "Ref Des/Silkscreen Top")
		(7 "B.SilkS" user "Ref Des/Silkscreen Bottom")
		(1 "F.Mask" user "Board Geometry/Soldermask Top")
		(3 "B.Mask" user "Board Geometry/Soldermask Bottom")
		(17 "Dwgs.User" user "User.Drawings")
		(19 "Cmts.User" user "User.Comments")
		(21 "Eco1.User" user "User.Eco1")
		(23 "Eco2.User" user "User.Eco2")
		(25 "Edge.Cuts" user "Board Geometry/Outline")
		(27 "Margin" user)
		(31 "F.CrtYd" user "Package Geometry/Place Bound Top")
		(29 "B.CrtYd" user "Package Geometry/Place Bound Bottom")
		(35 "F.Fab" user "Ref Des/Assembly Top")
		(33 "B.Fab" user "Ref Des/Assembly Bottom")
	)
	(footprint ""
		(layer "B.Cu")
		(at 59.563762 -347.780356 -90)
		(property "Reference" "PR264"
			(at 0 0 90)
			(layer "B.SilkS")
			(hide yes)
			(effects
				(font
					(size 1.27 1.27)
				)
				(justify mirror)
			)
		)
		(property "Value" ""
			(at 0 0 90)
			(layer "B.Fab")
			(effects
				(font
					(size 1.27 1.27)
				)
				(justify mirror)
			)
		)
		(duplicate_pad_numbers_are_jumpers no)
		(fp_line
			(start -0.7874 0.4064)
			(end 0.7874 0.4064)
			(stroke
				(width 0.1524)
				(type default)
			)
			(layer "B.SilkS")
		)
		(fp_line
			(start 0.7874 0.4064)
			(end 0.7874 -0.4064)
			(stroke
				(width 0.1524)
				(type default)
			)
			(layer "B.SilkS")
		)
		(fp_line
			(start -0.7874 -0.4064)
			(end -0.7874 0.4064)
			(stroke
				(width 0.1524)
				(type default)
			)
			(layer "B.SilkS")
		)
		(fp_line
			(start 0.7874 -0.4064)
			(end -0.7874 -0.4064)
			(stroke
				(width 0.1524)
				(type default)
			)
			(layer "B.SilkS")
		)
		(fp_line
			(start -0.67945 0.3048)
			(end -0.120396 0.3048)
			(stroke
				(width 0.1)
				(type default)
			)
			(layer "B.Fab")
		)
		(fp_line
			(start -0.120396 0.3048)
			(end -0.120396 0.2794)
			(stroke
				(width 0.1)
				(type default)
			)
			(layer "B.Fab")
		)
		(fp_line
			(start 0.12065 0.3048)
			(end 0.67945 0.3048)
			(stroke
				(width 0.1)
				(type default)
			)
			(layer "B.Fab")
		)
		(fp_line
			(start 0.67945 0.3048)
			(end 0.67945 -0.305054)
			(stroke
				(width 0.1)
				(type default)
			)
			(layer "B.Fab")
		)
		(fp_line
			(start -0.120396 0.2794)
			(end 0.12065 0.2794)
			(stroke
				(width 0.1)
				(type default)
			)
			(layer "B.Fab")
		)
		(fp_line
			(start 0.12065 0.2794)
			(end 0.12065 0.3048)
			(stroke
				(width 0.1)
				(type default)
			)
			(layer "B.Fab")
		)
		(fp_line
			(start -0.12065 -0.2794)
			(end -0.12065 -0.3048)
			(stroke
				(width 0.1)
				(type default)
			)
			(layer "B.Fab")
		)
		(fp_line
			(start 0.12065 -0.2794)
			(end -0.12065 -0.2794)
			(stroke
				(width 0.1)
				(type default)
			)
			(layer "B.Fab")
		)
		(fp_line
			(start -0.67945 -0.3048)
			(end -0.67945 0.3048)
			(stroke
				(width 0.1)
				(type default)
			)
			(layer "B.Fab")
		)
		(fp_line
			(start -0.12065 -0.3048)
			(end -0.67945 -0.3048)
			(stroke
				(width 0.1)
				(type default)
			)
			(layer "B.Fab")
		)
		(fp_line
			(start 0.12065 -0.305054)
			(end 0.12065 -0.2794)
			(stroke
				(width 0.1)
				(type default)
			)
			(layer "B.Fab")
		)
		(fp_line
			(start 0.67945 -0.305054)
			(end 0.12065 -0.305054)
			(stroke
				(width 0.1)
				(type default)
			)
			(layer "B.Fab")
		)
		(pad "1" smd circle
			(at 0.40005 0 90)
			(size 0 0)
			(layers "B.Cu" "B.Mask" "B.Paste")
			(net "PVDDCR_CPU1_P1_PVCC")
		)
		(pad "2" smd circle
			(at -0.40005 0 90)
			(size 0 0)
			(layers "B.Cu" "B.Mask" "B.Paste")
			(net "PVDDCR_CPU1_P1_VCC4")
		)
	)
	(footprint ""
		(layer "B.Cu")
		(at 363.034834 -398.055084 90)
		(property "Reference" "C1028"
			(at 0 0 90)
			(layer "B.SilkS")
			(hide yes)
			(effects
				(font
					(size 1.27 1.27)
				)
				(justify mirror)
			)
		)
		(property "Value" ""
			(at 0 0 90)
			(layer "B.Fab")
			(effects
				(font
					(size 1.27 1.27)
				)
				(justify mirror)
			)
		)
		(duplicate_pad_numbers_are_jumpers no)
		(fp_line
			(start 1.524 -0.762)
			(end -1.524 -0.762)
			(stroke
				(width 0.1524)
				(type default)
			)
			(layer "B.SilkS")
		)
		(fp_line
			(start -1.524 -0.762)
			(end -1.524 0.762)
			(stroke
				(width 0.1524)
				(type default)
			)
			(layer "B.SilkS")
		)
		(fp_line
			(start 1.524 0.762)
			(end 1.524 -0.762)
			(stroke
				(width 0.1524)
				(type default)
			)
			(layer "B.SilkS")
		)
		(fp_line
			(start -1.524 0.762)
			(end 1.524 0.762)
			(stroke
				(width 0.1524)
				(type default)
			)
			(layer "B.SilkS")
		)
		(fp_line
			(start 1.1049 -0.724916)
			(end 1.1049 0.724916)
			(stroke
				(width 0.1)
				(type default)
			)
			(layer "B.Fab")
		)
		(fp_line
			(start -1.1049 -0.724916)
			(end 1.1049 -0.724916)
			(stroke
				(width 0.1)
				(type default)
			)
			(layer "B.Fab")
		)
		(fp_line
			(start 1.1049 0.724916)
			(end -1.1049 0.724916)
			(stroke
				(width 0.1)
				(type default)
			)
			(layer "B.Fab")
		)
		(fp_line
			(start -1.1049 0.724916)
			(end -1.1049 -0.724916)
			(stroke
				(width 0.1)
				(type default)
			)
			(layer "B.Fab")
		)
		(pad "1" smd rect
			(at 0.889 0 90)
			(size 1.016 1.27)
			(layers "B.Cu" "B.Mask" "B.Paste")
			(net "P0V9_CPU0_RT_2D")
		)
		(pad "2" smd rect
			(at -0.889 0 90)
			(size 1.016 1.27)
			(layers "B.Cu" "B.Mask" "B.Paste")
			(net "GND")
		)
	)
	(footprint ""
		(layer "B.Cu")
		(at 331.793342 -393.96416 180)
		(property "Reference" "R1031"
			(at 0 0 0)
			(layer "B.SilkS")
			(hide yes)
			(effects
				(font
					(size 1.27 1.27)
				)
				(justify mirror)
			)
		)
		(property "Value" ""
			(at 0 0 0)
			(layer "B.Fab")
			(effects
				(font
					(size 1.27 1.27)
				)
				(justify mirror)
			)
		)
		(duplicate_pad_numbers_are_jumpers no)
		(fp_line
			(start 0.32512 0.175006)
			(end 0.32512 -0.175006)
			(stroke
				(width 0.1)
				(type default)
			)
			(layer "B.Fab")
		)
		(fp_line
			(start 0.32512 -0.175006)
			(end -0.32512 -0.175006)
			(stroke
				(width 0.1)
				(type default)
			)
			(layer "B.Fab")
		)
		(fp_line
			(start -0.32512 0.175006)
			(end 0.32512 0.175006)
			(stroke
				(width 0.1)
				(type default)
			)
			(layer "B.Fab")
		)
		(fp_line
			(start -0.32512 -0.175006)
			(end -0.32512 0.175006)
			(stroke
				(width 0.1)
				(type default)
			)
			(layer "B.Fab")
		)
		(pad "1" smd rect
			(at 0.2667 0)
			(size 0.3048 0.381)
			(layers "B.Cu" "B.Mask" "B.Paste")
			(net "TEST0_RT_CPU0_P1")
		)
		(pad "2" smd rect
			(at -0.2667 0 180)
			(size 0.3048 0.381)
			(layers "B.Cu" "B.Mask" "B.Paste")
			(net "GND")
		)
	)
)
